# T6G (Grand Teton) — schematic netlist excerpt (pin names and nets, part order shuffled) for the footprints in the layout excerpt that follows; sources: Cadence DE-HDL packaged netlist, KiCad conversion of 04192023_DAF0TMB3IC0_F0TG_MB_C_brd_V02_OCP.brd

R8299  Q_RES  33 5% CHIP  pkg 0402LF  page 193 : A = PWRGD_PVDDCR_SOC_P0 ; B = PWRGD_PVDDCR_SOC_P0_R
PC222  Q_CAP  0.1UF 25V 10% X7R  pkg 0402  page 208 : A = PVDD11_S3_P0 ; B = GND

(kicad_pcb
	(version 20260206)
	(generator "pcbnew")
	(generator_version "10.0")
	(general
		(thickness 1.6)
		(legacy_teardrops no)
	)
	(paper "A4")
	(title_block
		(title "04192023_DAF0TMB3IC0_F0TG_MB_C_brd_V02_OCP.brd")
		(comment 1 "Grand Teton / footprints 32-33 of 8354")
	)
	(layers
		(0 "F.Cu" signal "TOP")
		(4 "In1.Cu" signal "GND")
		(6 "In2.Cu" signal "IN1")
		(8 "In3.Cu" signal "GND1")
		(10 "In4.Cu" signal "IN2")
		(12 "In5.Cu" signal "GND2")
		(14 "In6.Cu" signal "IN3")
		(16 "In7.Cu" signal "GND3")
		(18 "In8.Cu" signal "VCC")
		(20 "In9.Cu" signal "VCC1")
		(22 "In10.Cu" signal "GND4")
		(24 "In11.Cu" signal "IN4")
		(26 "In12.Cu" signal "GND5")
		(28 "In13.Cu" signal "IN5")
		(30 "In14.Cu" signal "GND6")
		(32 "In15.Cu" signal "IN6")
		(34 "In16.Cu" signal "GND7")
		(2 "B.Cu" signal "BOTTOM")
		(9 "F.Adhes" user "F.Adhesive")
		(11 "B.Adhes" user "B.Adhesive")
		(13 "F.Paste" user "Package Geometry/Pastemask Top")
		(15 "B.Paste" user "Package Geometry/Pastemask Bottom")
		(5 "F.SilkS" user "Ref Des/Silkscreen Top")
		(7 "B.SilkS" user "Ref Des/Silkscreen Bottom")
		(1 "F.Mask" user "Board Geometry/Soldermask Top")
		(3 "B.Mask" user "Board Geometry/Soldermask Bottom")
		(17 "Dwgs.User" user "User.Drawings")
		(19 "Cmts.User" user "User.Comments")
		(21 "Eco1.User" user "User.Eco1")
		(23 "Eco2.User" user "User.Eco2")
		(25 "Edge.Cuts" user "Board Geometry/Outline")
		(27 "Margin" user)
		(31 "F.CrtYd" user "Package Geometry/Place Bound Top")
		(29 "B.CrtYd" user "Package Geometry/Place Bound Bottom")
		(35 "F.Fab" user "Ref Des/Assembly Top")
		(33 "B.Fab" user "Ref Des/Assembly Bottom")
	)
	(footprint ""
		(layer "F.Cu")
		(at 372.937278 -143.504158)
		(property "Reference" "R8299"
			(at 0 0 0)
			(layer "F.SilkS")
			(hide yes)
			(effects
				(font
					(size 1.27 1.27)
				)
			)
		)
		(property "Value" ""
			(at 0 0 0)
			(layer "F.Fab")
			(effects
				(font
					(size 1.27 1.27)
				)
			)
		)
		(duplicate_pad_numbers_are_jumpers no)
		(fp_line
			(start -0.7874 -0.4064)
			(end 0.7874 -0.4064)
			(stroke
				(width 0.1524)
				(type default)
			)
			(layer "F.SilkS")
		)
		(fp_line
			(start -0.7874 0.4064)
			(end -0.7874 -0.4064)
			(stroke
				(width 0.1524)
				(type default)
			)
			(layer "F.SilkS")
		)
		(fp_line
			(start 0.7874 -0.4064)
			(end 0.7874 0.4064)
			(stroke
				(width 0.1524)
				(type default)
			)
			(layer "F.SilkS")
		)
		(fp_line
			(start 0.7874 0.4064)
			(end -0.7874 0.4064)
			(stroke
				(width 0.1524)
				(type default)
			)
			(layer "F.SilkS")
		)
		(fp_line
			(start -0.67945 -0.305054)
			(end -0.12065 -0.305054)
			(stroke
				(width 0.1)
				(type default)
			)
			(layer "F.Fab")
		)
		(fp_line
			(start -0.67945 0.3048)
			(end -0.67945 -0.305054)
			(stroke
				(width 0.1)
				(type default)
			)
			(layer "F.Fab")
		)
		(fp_line
			(start -0.12065 -0.305054)
			(end -0.12065 -0.2794)
			(stroke
				(width 0.1)
				(type default)
			)
			(layer "F.Fab")
		)
		(fp_line
			(start -0.12065 -0.2794)
			(end 0.12065 -0.2794)
			(stroke
				(width 0.1)
				(type default)
			)
			(layer "F.Fab")
		)
		(fp_line
			(start -0.12065 0.2794)
			(end -0.12065 0.3048)
			(stroke
				(width 0.1)
				(type default)
			)
			(layer "F.Fab")
		)
		(fp_line
			(start -0.12065 0.3048)
			(end -0.67945 0.3048)
			(stroke
				(width 0.1)
				(type default)
			)
			(layer "F.Fab")
		)
		(fp_line
			(start 0.120396 0.2794)
			(end -0.12065 0.2794)
			(stroke
				(width 0.1)
				(type default)
			)
			(layer "F.Fab")
		)
		(fp_line
			(start 0.120396 0.3048)
			(end 0.120396 0.2794)
			(stroke
				(width 0.1)
				(type default)
			)
			(layer "F.Fab")
		)
		(fp_line
			(start 0.12065 -0.3048)
			(end 0.67945 -0.3048)
			(stroke
				(width 0.1)
				(type default)
			)
			(layer "F.Fab")
		)
		(fp_line
			(start 0.12065 -0.2794)
			(end 0.12065 -0.3048)
			(stroke
				(width 0.1)
				(type default)
			)
			(layer "F.Fab")
		)
		(fp_line
			(start 0.67945 -0.3048)
			(end 0.67945 0.3048)
			(stroke
				(width 0.1)
				(type default)
			)
			(layer "F.Fab")
		)
		(fp_line
			(start 0.67945 0.3048)
			(end 0.120396 0.3048)
			(stroke
				(width 0.1)
				(type default)
			)
			(layer "F.Fab")
		)
		(pad "1" smd circle
			(at -0.40005 0)
			(size 0 0)
			(layers "F.Cu" "F.Mask" "F.Paste")
			(net "PWRGD_PVDDCR_SOC_P0")
		)
		(pad "2" smd circle
			(at 0.40005 0)
			(size 0 0)
			(layers "F.Cu" "F.Mask" "F.Paste")
			(net "PWRGD_PVDDCR_SOC_P0_R")
		)
	)
	(footprint ""
		(layer "F.Cu")
		(at 417.018216 -332.628494 -90)
		(property "Reference" "PC222"
			(at 0 0 270)
			(layer "F.SilkS")
			(hide yes)
			(effects
				(font
					(size 1.27 1.27)
				)
			)
		)
		(property "Value" ""
			(at 0 0 270)
			(layer "F.Fab")
			(effects
				(font
					(size 1.27 1.27)
				)
			)
		)
		(duplicate_pad_numbers_are_jumpers no)
		(fp_line
			(start -0.7874 0.4064)
			(end -0.7874 -0.4064)
			(stroke
				(width 0.1524)
				(type default)
			)
			(layer "F.SilkS")
		)
		(fp_line
			(start 0.7874 0.4064)
			(end -0.7874 0.4064)
			(stroke
				(width 0.1524)
				(type default)
			)
			(layer "F.SilkS")
		)
		(fp_line
			(start -0.7874 -0.4064)
			(end 0.7874 -0.4064)
			(stroke
				(width 0.1524)
				(type default)
			)
			(layer "F.SilkS")
		)
		(fp_line
			(start 0.7874 -0.4064)
			(end 0.7874 0.4064)
			(stroke
				(width 0.1524)
				(type default)
			)
			(layer "F.SilkS")
		)
		(fp_line
			(start -0.67945 0.3048)
			(end -0.67945 -0.305054)
			(stroke
				(width 0.1)
				(type default)
			)
			(layer "F.Fab")
		)
		(fp_line
			(start -0.12065 0.3048)
			(end -0.67945 0.3048)
			(stroke
				(width 0.1)
				(type default)
			)
			(layer "F.Fab")
		)
		(fp_line
			(start 0.120396 0.3048)
			(end 0.120396 0.2794)
			(stroke
				(width 0.1)
				(type default)
			)
			(layer "F.Fab")
		)
		(fp_line
			(start 0.67945 0.3048)
			(end 0.120396 0.3048)
			(stroke
				(width 0.1)
				(type default)
			)
			(layer "F.Fab")
		)
		(fp_line
			(start -0.12065 0.2794)
			(end -0.12065 0.3048)
			(stroke
				(width 0.1)
				(type default)
			)
			(layer "F.Fab")
		)
		(fp_line
			(start 0.120396 0.2794)
			(end -0.12065 0.2794)
			(stroke
				(width 0.1)
				(type default)
			)
			(layer "F.Fab")
		)
		(fp_line
			(start -0.12065 -0.2794)
			(end 0.12065 -0.2794)
			(stroke
				(width 0.1)
				(type default)
			)
			(layer "F.Fab")
		)
		(fp_line
			(start 0.12065 -0.2794)
			(end 0.12065 -0.3048)
			(stroke
				(width 0.1)
				(type default)
			)
			(layer "F.Fab")
		)
		(fp_line
			(start 0.12065 -0.3048)
			(end 0.67945 -0.3048)
			(stroke
				(width 0.1)
				(type default)
			)
			(layer "F.Fab")
		)
		(fp_line
			(start 0.67945 -0.3048)
			(end 0.67945 0.3048)
			(stroke
				(width 0.1)
				(type default)
			)
			(layer "F.Fab")
		)
		(fp_line
			(start -0.67945 -0.305054)
			(end -0.12065 -0.305054)
			(stroke
				(width 0.1)
				(type default)
			)
			(layer "F.Fab")
		)
		(fp_line
			(start -0.12065 -0.305054)
			(end -0.12065 -0.2794)
			(stroke
				(width 0.1)
				(type default)
			)
			(layer "F.Fab")
		)
		(pad "1" smd circle
			(at -0.40005 0 270)
			(size 0 0)
			(layers "F.Cu" "F.Mask" "F.Paste")
			(net "PVDD11_S3_P0")
		)
		(pad "2" smd circle
			(at 0.40005 0 270)
			(size 0 0)
			(layers "F.Cu" "F.Mask" "F.Paste")
			(net "GND")
		)
	)
)
